# SCM (Grand Teton) — schematic netlist excerpt (pin names and nets, part order shuffled) for the footprints in the layout excerpt that follows; sources: Cadence DE-HDL packaged netlist, KiCad conversion of 12092022_DA0F0TMDCD0_F0T_Management_Board_D_brd_V3_OCP.brd

R531  Q_RES  33.2 1% EMPTY  pkg 0402LF  page 35 : A = BMC_CPLD_GPIO_8_R2 ; B = BMC_CPLD_GPIO_8
PR534  Q_RES  56K 1% CHIP  pkg 0402LF  page 52 : A = P3V3_AUX_FB_RC ; B = P3V3_AUX

(kicad_pcb
	(version 20260206)
	(generator "pcbnew")
	(generator_version "10.0")
	(general
		(thickness 1.6)
		(legacy_teardrops no)
	)
	(paper "A4")
	(title_block
		(title "12092022_DA0F0TMDCD0_F0T_Management_Board_D_brd_V3_OCP.brd")
		(comment 1 "Grand Teton / footprints 1-2 of 1440")
	)
	(layers
		(0 "F.Cu" signal "TOP")
		(4 "In1.Cu" signal "GND")
		(6 "In2.Cu" signal "IN1")
		(8 "In3.Cu" signal "GND1")
		(10 "In4.Cu" signal "IN2")
		(12 "In5.Cu" signal "VCC")
		(14 "In6.Cu" signal "VCC1")
		(16 "In7.Cu" signal "IN3")
		(18 "In8.Cu" signal "GND2")
		(20 "In9.Cu" signal "IN4")
		(22 "In10.Cu" signal "GND3")
		(2 "B.Cu" signal "BOTTOM")
		(9 "F.Adhes" user "F.Adhesive")
		(11 "B.Adhes" user "B.Adhesive")
		(13 "F.Paste" user "Package Geometry/Pastemask Top")
		(15 "B.Paste" user "Package Geometry/Pastemask Bottom")
		(5 "F.SilkS" user "Ref Des/Silkscreen Top")
		(7 "B.SilkS" user "Ref Des/Silkscreen Bottom")
		(1 "F.Mask" user "Board Geometry/Soldermask Top")
		(3 "B.Mask" user "Board Geometry/Soldermask Bottom")
		(17 "Dwgs.User" user "User.Drawings")
		(19 "Cmts.User" user "User.Comments")
		(21 "Eco1.User" user "User.Eco1")
		(23 "Eco2.User" user "User.Eco2")
		(25 "Edge.Cuts" user "Board Geometry/Outline")
		(27 "Margin" user)
		(31 "F.CrtYd" user "Package Geometry/Place Bound Top")
		(29 "B.CrtYd" user "Package Geometry/Place Bound Bottom")
		(35 "F.Fab" user "Ref Des/Assembly Top")
		(33 "B.Fab" user "Ref Des/Assembly Bottom")
	)
	(footprint ""
		(layer "F.Cu")
		(at 12.319 -93.472 180)
		(property "Reference" "R531"
			(at 0 0 180)
			(layer "F.SilkS")
			(hide yes)
			(effects
				(font
					(size 1.27 1.27)
				)
			)
		)
		(property "Value" ""
			(at 0 0 180)
			(layer "F.Fab")
			(effects
				(font
					(size 1.27 1.27)
				)
			)
		)
		(duplicate_pad_numbers_are_jumpers no)
		(fp_line
			(start 0.7874 0.4064)
			(end -0.7874 0.4064)
			(stroke
				(width 0.1524)
				(type default)
			)
			(layer "F.SilkS")
		)
		(fp_line
			(start 0.7874 -0.4064)
			(end 0.7874 0.4064)
			(stroke
				(width 0.1524)
				(type default)
			)
			(layer "F.SilkS")
		)
		(fp_line
			(start -0.7874 0.4064)
			(end -0.7874 -0.4064)
			(stroke
				(width 0.1524)
				(type default)
			)
			(layer "F.SilkS")
		)
		(fp_line
			(start -0.7874 -0.4064)
			(end 0.7874 -0.4064)
			(stroke
				(width 0.1524)
				(type default)
			)
			(layer "F.SilkS")
		)
		(fp_line
			(start 0.67945 0.3048)
			(end 0.120396 0.3048)
			(stroke
				(width 0.1)
				(type default)
			)
			(layer "F.Fab")
		)
		(fp_line
			(start 0.67945 -0.3048)
			(end 0.67945 0.3048)
			(stroke
				(width 0.1)
				(type default)
			)
			(layer "F.Fab")
		)
		(fp_line
			(start 0.12065 -0.2794)
			(end 0.12065 -0.3048)
			(stroke
				(width 0.1)
				(type default)
			)
			(layer "F.Fab")
		)
		(fp_line
			(start 0.12065 -0.3048)
			(end 0.67945 -0.3048)
			(stroke
				(width 0.1)
				(type default)
			)
			(layer "F.Fab")
		)
		(fp_line
			(start 0.120396 0.3048)
			(end 0.120396 0.2794)
			(stroke
				(width 0.1)
				(type default)
			)
			(layer "F.Fab")
		)
		(fp_line
			(start 0.120396 0.2794)
			(end -0.12065 0.2794)
			(stroke
				(width 0.1)
				(type default)
			)
			(layer "F.Fab")
		)
		(fp_line
			(start -0.12065 0.3048)
			(end -0.67945 0.3048)
			(stroke
				(width 0.1)
				(type default)
			)
			(layer "F.Fab")
		)
		(fp_line
			(start -0.12065 0.2794)
			(end -0.12065 0.3048)
			(stroke
				(width 0.1)
				(type default)
			)
			(layer "F.Fab")
		)
		(fp_line
			(start -0.12065 -0.2794)
			(end 0.12065 -0.2794)
			(stroke
				(width 0.1)
				(type default)
			)
			(layer "F.Fab")
		)
		(fp_line
			(start -0.12065 -0.305054)
			(end -0.12065 -0.2794)
			(stroke
				(width 0.1)
				(type default)
			)
			(layer "F.Fab")
		)
		(fp_line
			(start -0.67945 0.3048)
			(end -0.67945 -0.305054)
			(stroke
				(width 0.1)
				(type default)
			)
			(layer "F.Fab")
		)
		(fp_line
			(start -0.67945 -0.305054)
			(end -0.12065 -0.305054)
			(stroke
				(width 0.1)
				(type default)
			)
			(layer "F.Fab")
		)
		(pad "1" smd circle
			(at -0.40005 0 180)
			(size 0 0)
			(layers "F.Cu" "F.Mask" "F.Paste")
			(net "BMC_CPLD_GPIO_8_R2")
		)
		(pad "2" smd circle
			(at 0.40005 0 180)
			(size 0 0)
			(layers "F.Cu" "F.Mask" "F.Paste")
			(net "BMC_CPLD_GPIO_8")
		)
	)
	(footprint ""
		(layer "F.Cu")
		(at 13.31976 -64.54394 90)
		(property "Reference" "PR534"
			(at 0 0 90)
			(layer "F.SilkS")
			(hide yes)
			(effects
				(font
					(size 1.27 1.27)
				)
			)
		)
		(property "Value" ""
			(at 0 0 90)
			(layer "F.Fab")
			(effects
				(font
					(size 1.27 1.27)
				)
			)
		)
		(duplicate_pad_numbers_are_jumpers no)
		(fp_line
			(start 0.7874 -0.4064)
			(end 0.7874 0.4064)
			(stroke
				(width 0.1524)
				(type default)
			)
			(layer "F.SilkS")
		)
		(fp_line
			(start -0.7874 -0.4064)
			(end 0.7874 -0.4064)
			(stroke
				(width 0.1524)
				(type default)
			)
			(layer "F.SilkS")
		)
		(fp_line
			(start 0.7874 0.4064)
			(end -0.7874 0.4064)
			(stroke
				(width 0.1524)
				(type default)
			)
			(layer "F.SilkS")
		)
		(fp_line
			(start -0.7874 0.4064)
			(end -0.7874 -0.4064)
			(stroke
				(width 0.1524)
				(type default)
			)
			(layer "F.SilkS")
		)
		(fp_line
			(start -0.12065 -0.305054)
			(end -0.12065 -0.2794)
			(stroke
				(width 0.1)
				(type default)
			)
			(layer "F.Fab")
		)
		(fp_line
			(start -0.67945 -0.305054)
			(end -0.12065 -0.305054)
			(stroke
				(width 0.1)
				(type default)
			)
			(layer "F.Fab")
		)
		(fp_line
			(start 0.67945 -0.3048)
			(end 0.67945 0.3048)
			(stroke
				(width 0.1)
				(type default)
			)
			(layer "F.Fab")
		)
		(fp_line
			(start 0.12065 -0.3048)
			(end 0.67945 -0.3048)
			(stroke
				(width 0.1)
				(type default)
			)
			(layer "F.Fab")
		)
		(fp_line
			(start 0.12065 -0.2794)
			(end 0.12065 -0.3048)
			(stroke
				(width 0.1)
				(type default)
			)
			(layer "F.Fab")
		)
		(fp_line
			(start -0.12065 -0.2794)
			(end 0.12065 -0.2794)
			(stroke
				(width 0.1)
				(type default)
			)
			(layer "F.Fab")
		)
		(fp_line
			(start 0.120396 0.2794)
			(end -0.12065 0.2794)
			(stroke
				(width 0.1)
				(type default)
			)
			(layer "F.Fab")
		)
		(fp_line
			(start -0.12065 0.2794)
			(end -0.12065 0.3048)
			(stroke
				(width 0.1)
				(type default)
			)
			(layer "F.Fab")
		)
		(fp_line
			(start 0.67945 0.3048)
			(end 0.120396 0.3048)
			(stroke
				(width 0.1)
				(type default)
			)
			(layer "F.Fab")
		)
		(fp_line
			(start 0.120396 0.3048)
			(end 0.120396 0.2794)
			(stroke
				(width 0.1)
				(type default)
			)
			(layer "F.Fab")
		)
		(fp_line
			(start -0.12065 0.3048)
			(end -0.67945 0.3048)
			(stroke
				(width 0.1)
				(type default)
			)
			(layer "F.Fab")
		)
		(fp_line
			(start -0.67945 0.3048)
			(end -0.67945 -0.305054)
			(stroke
				(width 0.1)
				(type default)
			)
			(layer "F.Fab")
		)
		(pad "1" smd circle
			(at -0.40005 0 90)
			(size 0 0)
			(layers "F.Cu" "F.Mask" "F.Paste")
			(net "P3V3_AUX_FB_RC")
		)
		(pad "2" smd circle
			(at 0.40005 0 90)
			(size 0 0)
			(layers "F.Cu" "F.Mask" "F.Paste")
			(net "P3V3_AUX")
		)
	)
)
